# BASEBOARD_FAB2 (Tioga Pass) — schematic netlist excerpt (pin names and nets, part order shuffled) for the footprints in the layout excerpt that follows; sources: Cadence DE-HDL packaged netlist, KiCad conversion of Wiwynn_Tioga_Pass_MB.brd

C2D15  CAP_A  22.0UF 4V 20% X6S  pkg 0603V  page 76 : A = PVCCIN_CPU1 ; B = GND
C1C14  CAP_A  0.1UF 16V 10% X7R  pkg 0402V  page 206 : A = VR_PVCCIN_CPU1_VD12 ; B = GND

(kicad_pcb
	(version 20260206)
	(generator "pcbnew")
	(generator_version "10.0")
	(general
		(thickness 1.6)
		(legacy_teardrops no)
	)
	(paper "A4")
	(title_block
		(title "Wiwynn_Tioga_Pass_MB.brd")
		(comment 1 "Tioga Pass / footprints 924-926 of 4770")
	)
	(layers
		(0 "F.Cu" signal "TOP")
		(4 "In1.Cu" signal "L2GND")
		(6 "In2.Cu" signal "L3")
		(8 "In3.Cu" signal "L4GND")
		(10 "In4.Cu" signal "L5")
		(12 "In5.Cu" signal "L6GND")
		(14 "In6.Cu" signal "L7VCC")
		(16 "In7.Cu" signal "L8VCC")
		(18 "In8.Cu" signal "L9GND")
		(20 "In9.Cu" signal "L10")
		(22 "In10.Cu" signal "L11GND")
		(24 "In11.Cu" signal "L12")
		(26 "In12.Cu" signal "L13GND")
		(2 "B.Cu" signal "BOTTOM")
		(9 "F.Adhes" user "F.Adhesive")
		(11 "B.Adhes" user "B.Adhesive")
		(13 "F.Paste" user "Package Geometry/Pastemask Top")
		(15 "B.Paste" user "Package Geometry/Pastemask Bottom")
		(5 "F.SilkS" user "Ref Des/Silkscreen Top")
		(7 "B.SilkS" user "Ref Des/Silkscreen Bottom")
		(1 "F.Mask" user "Board Geometry/Soldermask Top")
		(3 "B.Mask" user "Board Geometry/Soldermask Bottom")
		(17 "Dwgs.User" user "User.Drawings")
		(19 "Cmts.User" user "User.Comments")
		(21 "Eco1.User" user "User.Eco1")
		(23 "Eco2.User" user "User.Eco2")
		(25 "Edge.Cuts" user "Board Geometry/Outline")
		(27 "Margin" user)
		(31 "F.CrtYd" user "Package Geometry/Place Bound Top")
		(29 "B.CrtYd" user "Package Geometry/Place Bound Bottom")
		(35 "F.Fab" user "Ref Des/Assembly Top")
		(33 "B.Fab" user "Ref Des/Assembly Bottom")
	)
	(footprint ""
		(layer "F.Cu")
		(at 14.605 -97.028 180)
		(property "Reference" "C1C14"
			(at 0 0 180)
			(layer "F.SilkS")
			(hide yes)
			(effects
				(font
					(size 1.27 1.27)
				)
			)
		)
		(property "Value" ""
			(at 0 0 180)
			(layer "F.Fab")
			(effects
				(font
					(size 1.27 1.27)
				)
			)
		)
		(duplicate_pad_numbers_are_jumpers no)
		(fp_rect
			(start 0.3048 -0.1016)
			(end -0.3048 0.9906)
			(stroke
				(width 0)
				(type default)
			)
			(fill no)
			(layer "F.CrtYd")
		)
		(fp_line
			(start 0.3048 0.9906)
			(end 0.3048 -0.1016)
			(stroke
				(width 0.1)
				(type default)
			)
			(layer "F.Fab")
		)
		(fp_line
			(start 0.3048 -0.1016)
			(end -0.3048 -0.1016)
			(stroke
				(width 0.1)
				(type default)
			)
			(layer "F.Fab")
		)
		(fp_line
			(start -0.3048 0.9906)
			(end 0.3048 0.9906)
			(stroke
				(width 0.1)
				(type default)
			)
			(layer "F.Fab")
		)
		(fp_line
			(start -0.3048 -0.1016)
			(end -0.3048 0.9906)
			(stroke
				(width 0.1)
				(type default)
			)
			(layer "F.Fab")
		)
		(pad "1" smd rect
			(at 0 0 180)
			(size 0.508 0.508)
			(layers "F.Cu" "F.Mask" "F.Paste")
			(net "VR_PVCCIN_CPU1_VD12")
		)
		(pad "2" smd rect
			(at 0 0.889 180)
			(size 0.508 0.508)
			(layers "F.Cu" "F.Mask" "F.Paste")
			(net "GND")
		)
		(zone
			(layer "F.Cu")
			(hatch none 0.5)
			(connect_pads
				(clearance 0)
			)
			(min_thickness 0.25)
			(keepout
				(tracks allowed)
				(vias not_allowed)
				(pads allowed)
				(copperpour not_allowed)
				(footprints allowed)
			)
			(placement
				(enabled no)
				(sheetname "")
			)
			(fill
				(thermal_gap 0.5)
				(thermal_bridge_width 0.5)
				(island_removal_mode 0)
			)
			(polygon
				(pts
					(xy 14.351 -97.282) (xy 14.859 -97.282) (xy 14.859 -97.663) (xy 14.351 -97.663)
				)
			)
		)
		(zone
			(layer "F.Cu")
			(hatch none 0.5)
			(connect_pads
				(clearance 0)
			)
			(min_thickness 0.25)
			(keepout
				(tracks not_allowed)
				(vias allowed)
				(pads allowed)
				(copperpour not_allowed)
				(footprints allowed)
			)
			(placement
				(enabled no)
				(sheetname "")
			)
			(fill
				(thermal_gap 0.5)
				(thermal_bridge_width 0.5)
				(island_removal_mode 0)
			)
			(polygon
				(pts
					(xy 14.351 -97.282) (xy 14.859 -97.282) (xy 14.859 -97.663) (xy 14.351 -97.663)
				)
			)
		)
	)
	(footprint ""
		(layer "F.Cu")
		(at 202.184 -26.162)
		(property "Reference" ""
			(at 0 0 0)
			(layer "F.SilkS")
			(hide yes)
			(effects
				(font
					(size 1.27 1.27)
				)
			)
		)
		(property "Value" ""
			(at 0 0 0)
			(layer "F.Fab")
			(effects
				(font
					(size 1.27 1.27)
				)
			)
		)
		(duplicate_pad_numbers_are_jumpers no)
		(fp_poly
			(pts
				(arc
					(start 2.032 0)
					(mid -2.032 0)
					(end 2.032 0)
				)
			)
			(stroke
				(width 0)
				(type default)
			)
			(fill no)
			(layer "F.CrtYd")
		)
		(pad "1" smd circle
			(at 0 0)
			(size 1.016 1.016)
			(layers "F.Cu" "F.Mask" "F.Paste")
			(net "Net_391")
		)
		(zone
			(layer "F.Cu")
			(hatch none 0.5)
			(connect_pads
				(clearance 0)
			)
			(min_thickness 0.25)
			(keepout
				(tracks not_allowed)
				(vias allowed)
				(pads allowed)
				(copperpour not_allowed)
				(footprints allowed)
			)
			(placement
				(enabled no)
				(sheetname "")
			)
			(fill
				(thermal_gap 0.5)
				(thermal_bridge_width 0.5)
				(island_removal_mode 0)
			)
			(polygon
				(pts
					(arc
						(start 203.708 -26.162)
						(mid 200.66 -26.162)
						(end 203.708 -26.162)
					)
				)
			)
		)
		(zone
			(layers "F.Cu" "B.Cu" "In1.Cu" "In2.Cu" "In3.Cu" "In4.Cu" "In5.Cu" "In6.Cu"
				"In7.Cu" "In8.Cu" "In9.Cu" "In10.Cu" "In11.Cu" "In12.Cu"
			)
			(hatch none 0.5)
			(connect_pads
				(clearance 0)
			)
			(min_thickness 0.25)
			(keepout
				(tracks allowed)
				(vias not_allowed)
				(pads allowed)
				(copperpour not_allowed)
				(footprints allowed)
			)
			(placement
				(enabled no)
				(sheetname "")
			)
			(fill
				(thermal_gap 0.5)
				(thermal_bridge_width 0.5)
				(island_removal_mode 0)
			)
			(polygon
				(pts
					(arc
						(start 203.708 -26.162)
						(mid 200.66 -26.162)
						(end 203.708 -26.162)
					)
				)
			)
		)
	)
	(footprint ""
		(layer "F.Cu")
		(at 100.683568 -79.6036 180)
		(property "Reference" "C2D15"
			(at 0 0 180)
			(layer "F.SilkS")
			(hide yes)
			(effects
				(font
					(size 1.27 1.27)
				)
			)
		)
		(property "Value" ""
			(at 0 0 180)
			(layer "F.Fab")
			(effects
				(font
					(size 1.27 1.27)
				)
			)
		)
		(duplicate_pad_numbers_are_jumpers no)
		(fp_poly
			(pts
				(xy -0.4953 -0.2032) (xy 0.4953 -0.2032) (xy 0.4953 1.6002) (xy -0.4953 1.6002)
			)
			(stroke
				(width 0)
				(type default)
			)
			(fill no)
			(layer "F.CrtYd")
		)
		(fp_line
			(start 0.4953 1.6002)
			(end -0.4953 1.6002)
			(stroke
				(width 0.1)
				(type default)
			)
			(layer "F.Fab")
		)
		(fp_line
			(start 0.4953 -0.2032)
			(end 0.4953 1.6002)
			(stroke
				(width 0.1)
				(type default)
			)
			(layer "F.Fab")
		)
		(fp_line
			(start -0.4953 1.6002)
			(end -0.4953 -0.2032)
			(stroke
				(width 0.1)
				(type default)
			)
			(layer "F.Fab")
		)
		(fp_line
			(start -0.4953 -0.2032)
			(end 0.4953 -0.2032)
			(stroke
				(width 0.1)
				(type default)
			)
			(layer "F.Fab")
		)
		(pad "1" smd rect
			(at 0 0 180)
			(size 0.762 0.889)
			(layers "F.Cu" "F.Mask" "F.Paste")
			(net "PVCCIN_CPU1")
		)
		(pad "2" smd rect
			(at 0 1.397 180)
			(size 0.762 0.889)
			(layers "F.Cu" "F.Mask" "F.Paste")
			(net "GND")
		)
		(zone
			(layer "F.Cu")
			(hatch none 0.5)
			(connect_pads
				(clearance 0)
			)
			(min_thickness 0.25)
			(keepout
				(tracks not_allowed)
				(vias allowed)
				(pads allowed)
				(copperpour not_allowed)
				(footprints allowed)
			)
			(placement
				(enabled no)
				(sheetname "")
			)
			(fill
				(thermal_gap 0.5)
				(thermal_bridge_width 0.5)
				(island_removal_mode 0)
			)
			(polygon
				(pts
					(xy 101.064568 -80.0481) (xy 100.302568 -80.0481) (xy 100.302568 -80.5561) (xy 101.064568 -80.5561)
				)
			)
		)
	)
)
